# S9S_MB_2U (Grand Teton) — schematic netlist excerpt (pin names and nets, part order shuffled) for the footprints in the layout excerpt that follows; sources: Cadence DE-HDL packaged netlist, KiCad conversion of 03242023_DA0F0TMBIJ0_F0T_Motherboard_J_brd_V01_OCP.brd

U266  INA230AIRGTR  IC  pkg QFN16_THXI  page 171
  A1  = INA230_1_A1
  A0  = INA230_1_A0
  ALERT  = OCP_SFF_P3V3_ADC_ALERT_R
  SDA  = SMB_INA230_1_3V3AUX_SDA_R1
  SCL  = SMB_INA230_1_3V3AUX_SCL_R1
  NC0  = NC_INA230_1_NC0
  NC1  = NC_INA230_1_NC1
  NC2  = NC_INA230_1_NC2
  VS  = P3V3_AUX
  GND  = GND
  \bus\  = P3V3_OCP_SFF_R
  \in-\  = VSENSE_P3V3_INA230_1_INN
  \in+\  = VSENSE_P3V3_INA230_1_INP
  NC3  = NC_INA230_1_NC3
  NC4  = NC_INA230_1_NC4
  NC5  = NC_INA230_1_NC5
  TH  = GND

(kicad_pcb
	(version 20260206)
	(generator "pcbnew")
	(generator_version "10.0")
	(general
		(thickness 1.6)
		(legacy_teardrops no)
	)
	(paper "A4")
	(title_block
		(title "03242023_DA0F0TMBIJ0_F0T_Motherboard_J_brd_V01_OCP.brd")
		(comment 1 "Grand Teton / footprints 1292-1292 of 6105")
	)
	(layers
		(0 "F.Cu" signal "TOP")
		(4 "In1.Cu" signal "GND")
		(6 "In2.Cu" signal "IN1")
		(8 "In3.Cu" signal "GND1")
		(10 "In4.Cu" signal "IN2")
		(12 "In5.Cu" signal "GND2")
		(14 "In6.Cu" signal "IN3")
		(16 "In7.Cu" signal "GND3")
		(18 "In8.Cu" signal "VCC")
		(20 "In9.Cu" signal "VCC1")
		(22 "In10.Cu" signal "GND4")
		(24 "In11.Cu" signal "IN4")
		(26 "In12.Cu" signal "GND5")
		(28 "In13.Cu" signal "IN5")
		(30 "In14.Cu" signal "GND6")
		(32 "In15.Cu" signal "IN6")
		(34 "In16.Cu" signal "GND7")
		(2 "B.Cu" signal "BOTTOM")
		(9 "F.Adhes" user "F.Adhesive")
		(11 "B.Adhes" user "B.Adhesive")
		(13 "F.Paste" user "Package Geometry/Pastemask Top")
		(15 "B.Paste" user "Package Geometry/Pastemask Bottom")
		(5 "F.SilkS" user "Ref Des/Silkscreen Top")
		(7 "B.SilkS" user "Ref Des/Silkscreen Bottom")
		(1 "F.Mask" user "Board Geometry/Soldermask Top")
		(3 "B.Mask" user "Board Geometry/Soldermask Bottom")
		(17 "Dwgs.User" user "User.Drawings")
		(19 "Cmts.User" user "User.Comments")
		(21 "Eco1.User" user "User.Eco1")
		(23 "Eco2.User" user "User.Eco2")
		(25 "Edge.Cuts" user "Board Geometry/Outline")
		(27 "Margin" user)
		(31 "F.CrtYd" user "Package Geometry/Place Bound Top")
		(29 "B.CrtYd" user "Package Geometry/Place Bound Bottom")
		(35 "F.Fab" user "Ref Des/Assembly Top")
		(33 "B.Fab" user "Ref Des/Assembly Bottom")
	)
	(footprint ""
		(layer "F.Cu")
		(at 440.687968 -94.077536 180)
		(property "Reference" "U266"
			(at 0.221996 2.912872 0)
			(unlocked yes)
			(layer "F.SilkS")
			(effects
				(font
					(size 0.7874 0.5842)
					(thickness 0.1524)
				)
			)
		)
		(property "Value" ""
			(at 0 0 180)
			(layer "F.Fab")
			(effects
				(font
					(size 1.27 1.27)
				)
			)
		)
		(duplicate_pad_numbers_are_jumpers no)
		(fp_line
			(start 1.500124 1.500124)
			(end 1.004062 1.500124)
			(stroke
				(width 0.1524)
				(type default)
			)
			(layer "F.SilkS")
		)
		(fp_line
			(start 1.500124 1.004062)
			(end 1.500124 1.500124)
			(stroke
				(width 0.1524)
				(type default)
			)
			(layer "F.SilkS")
		)
		(fp_line
			(start 1.500124 -1.500124)
			(end 1.500124 -1.004062)
			(stroke
				(width 0.1524)
				(type default)
			)
			(layer "F.SilkS")
		)
		(fp_line
			(start 1.004062 -1.500124)
			(end 1.500124 -1.500124)
			(stroke
				(width 0.1524)
				(type default)
			)
			(layer "F.SilkS")
		)
		(fp_line
			(start -1.004062 1.500124)
			(end -1.500124 1.500124)
			(stroke
				(width 0.1524)
				(type default)
			)
			(layer "F.SilkS")
		)
		(fp_line
			(start -1.500124 1.500124)
			(end -1.500124 1.004062)
			(stroke
				(width 0.1524)
				(type default)
			)
			(layer "F.SilkS")
		)
		(fp_line
			(start -1.500124 -1.004062)
			(end -1.500124 -1.500124)
			(stroke
				(width 0.1524)
				(type default)
			)
			(layer "F.SilkS")
		)
		(fp_line
			(start -1.500124 -1.500124)
			(end -1.004062 -1.500124)
			(stroke
				(width 0.1524)
				(type default)
			)
			(layer "F.SilkS")
		)
		(fp_poly
			(pts
				(xy -2.242312 -0.999744) (xy -1.783588 -0.770382) (xy -2.242312 -0.54102)
			)
			(stroke
				(width 0)
				(type default)
			)
			(fill yes)
			(layer "F.SilkS")
		)
		(fp_line
			(start 1.500124 1.500124)
			(end -1.500124 1.500124)
			(stroke
				(width 0.1)
				(type default)
			)
			(layer "F.Fab")
		)
		(fp_line
			(start 1.500124 -1.500124)
			(end 1.500124 1.500124)
			(stroke
				(width 0.1)
				(type default)
			)
			(layer "F.Fab")
		)
		(fp_line
			(start -1.500124 1.500124)
			(end -1.500124 -1.500124)
			(stroke
				(width 0.1)
				(type default)
			)
			(layer "F.Fab")
		)
		(fp_line
			(start -1.500124 -1.500124)
			(end 1.500124 -1.500124)
			(stroke
				(width 0.1)
				(type default)
			)
			(layer "F.Fab")
		)
		(fp_poly
			(pts
				(xy -2.847848 -1.258062) (xy -2.847848 -0.242062) (xy -1.831848 -0.750062)
			)
			(stroke
				(width 0)
				(type default)
			)
			(fill yes)
			(layer "F.Fab")
		)
		(pad "1" smd rect
			(at -1.400048 -0.750062 90)
			(size 0.2286 0.6096)
			(layers "F.Cu" "F.Mask" "F.Paste")
			(net "INA230_1_A1")
		)
		(pad "2" smd rect
			(at -1.400048 -0.249936 90)
			(size 0.2286 0.6096)
			(layers "F.Cu" "F.Mask" "F.Paste")
			(net "INA230_1_A0")
		)
		(pad "3" smd rect
			(at -1.400048 0.249936 90)
			(size 0.2286 0.6096)
			(layers "F.Cu" "F.Mask" "F.Paste")
			(net "OCP_SFF_P3V3_ADC_ALERT_R")
		)
		(pad "4" smd rect
			(at -1.400048 0.750062 90)
			(size 0.2286 0.6096)
			(layers "F.Cu" "F.Mask" "F.Paste")
			(net "SMB_INA230_1_3V3AUX_SDA_R1")
		)
		(pad "5" smd rect
			(at -0.750062 1.400048 180)
			(size 0.2286 0.6096)
			(layers "F.Cu" "F.Mask" "F.Paste")
			(net "SMB_INA230_1_3V3AUX_SCL_R1")
		)
		(pad "6" smd rect
			(at -0.249936 1.400048 180)
			(size 0.2286 0.6096)
			(layers "F.Cu" "F.Mask" "F.Paste")
			(net "NC_INA230_1_NC0")
		)
		(pad "7" smd rect
			(at 0.249936 1.400048 180)
			(size 0.2286 0.6096)
			(layers "F.Cu" "F.Mask" "F.Paste")
			(net "NC_INA230_1_NC1")
		)
		(pad "8" smd rect
			(at 0.750062 1.400048 180)
			(size 0.2286 0.6096)
			(layers "F.Cu" "F.Mask" "F.Paste")
			(net "NC_INA230_1_NC2")
		)
		(pad "9" smd rect
			(at 1.400048 0.750062 90)
			(size 0.2286 0.6096)
			(layers "F.Cu" "F.Mask" "F.Paste")
			(net "P3V3_AUX")
		)
		(pad "10" smd rect
			(at 1.400048 0.249936 90)
			(size 0.2286 0.6096)
			(layers "F.Cu" "F.Mask" "F.Paste")
			(net "GND")
		)
		(pad "11" smd rect
			(at 1.400048 -0.249936 90)
			(size 0.2286 0.6096)
			(layers "F.Cu" "F.Mask" "F.Paste")
			(net "P3V3_OCP_SFF_R")
		)
		(pad "12" smd rect
			(at 1.400048 -0.750062 90)
			(size 0.2286 0.6096)
			(layers "F.Cu" "F.Mask" "F.Paste")
			(net "VSENSE_P3V3_INA230_1_INN")
		)
		(pad "13" smd rect
			(at 0.750062 -1.400048 180)
			(size 0.2286 0.6096)
			(layers "F.Cu" "F.Mask" "F.Paste")
			(net "VSENSE_P3V3_INA230_1_INP")
		)
		(pad "14" smd rect
			(at 0.249936 -1.400048 180)
			(size 0.2286 0.6096)
			(layers "F.Cu" "F.Mask" "F.Paste")
			(net "NC_INA230_1_NC3")
		)
		(pad "15" smd rect
			(at -0.249936 -1.400048 180)
			(size 0.2286 0.6096)
			(layers "F.Cu" "F.Mask" "F.Paste")
			(net "NC_INA230_1_NC4")
		)
		(pad "16" smd rect
			(at -0.750062 -1.400048 180)
			(size 0.2286 0.6096)
			(layers "F.Cu" "F.Mask" "F.Paste")
			(net "NC_INA230_1_NC5")
		)
		(pad "TH" smd rect
			(at 0 0 180)
			(size 1.7018 1.7018)
			(layers "F.Cu" "F.Mask" "F.Paste")
			(net "GND")
		)
		(zone
			(layer "F.Cu")
			(hatch none 0.5)
			(connect_pads
				(clearance 0)
			)
			(min_thickness 0.25)
			(keepout
				(tracks not_allowed)
				(vias allowed)
				(pads allowed)
				(copperpour not_allowed)
				(footprints allowed)
			)
			(placement
				(enabled no)
				(sheetname "")
			)
			(fill
				(thermal_gap 0.5)
				(thermal_bridge_width 0.5)
				(island_removal_mode 0)
			)
			(polygon
				(pts
					(xy 441.732416 -94.052136) (xy 441.732416 -93.033088) (xy 439.64352 -93.033088) (xy 439.64352 -95.121984)
					(xy 441.732416 -95.121984) (xy 441.732416 -94.077536) (xy 441.589668 -94.077536) (xy 441.589668 -94.979236)
					(xy 439.786268 -94.979236) (xy 439.786268 -93.175836) (xy 441.589668 -93.175836) (xy 441.589668 -94.052136)
				)
			)
		)
	)
)
